# T6G (Grand Teton) — schematic netlist excerpt (pin names and nets, part order shuffled) for the footprints in the layout excerpt that follows; sources: Cadence DE-HDL packaged netlist, KiCad conversion of 04192023_DAF0TMB3IC0_F0TG_MB_C_brd_V02_OCP.brd

C6635  Q_CAP_DIFFBUS  DIFF BUS_0.22UF 6.3V 20% X6S  pkg C0201  page 319 : \1\ = P5E_CPU1_P0_TX_BUF_C_DP<3> ; \2\ = P5E_CPU1_P0_TX_BUF_DP<3>
R1634  Q_RES  0 5% CHIP  pkg 0402LF  page 172 : A = JTAG_TMS_R ; B = JTAG_TMS
R238  Q_RES  0 5% CHIP  pkg 0402LF  page 82 : A = CPU0_XTRIG_L6 ; B = FM_CPU0_XTRIG_L6

(kicad_pcb
	(version 20260206)
	(generator "pcbnew")
	(generator_version "10.0")
	(general
		(thickness 1.6)
		(legacy_teardrops no)
	)
	(paper "A4")
	(title_block
		(title "04192023_DAF0TMB3IC0_F0TG_MB_C_brd_V02_OCP.brd")
		(comment 1 "Grand Teton / footprints 1468-1470 of 8354")
	)
	(layers
		(0 "F.Cu" signal "TOP")
		(4 "In1.Cu" signal "GND")
		(6 "In2.Cu" signal "IN1")
		(8 "In3.Cu" signal "GND1")
		(10 "In4.Cu" signal "IN2")
		(12 "In5.Cu" signal "GND2")
		(14 "In6.Cu" signal "IN3")
		(16 "In7.Cu" signal "GND3")
		(18 "In8.Cu" signal "VCC")
		(20 "In9.Cu" signal "VCC1")
		(22 "In10.Cu" signal "GND4")
		(24 "In11.Cu" signal "IN4")
		(26 "In12.Cu" signal "GND5")
		(28 "In13.Cu" signal "IN5")
		(30 "In14.Cu" signal "GND6")
		(32 "In15.Cu" signal "IN6")
		(34 "In16.Cu" signal "GND7")
		(2 "B.Cu" signal "BOTTOM")
		(9 "F.Adhes" user "F.Adhesive")
		(11 "B.Adhes" user "B.Adhesive")
		(13 "F.Paste" user "Package Geometry/Pastemask Top")
		(15 "B.Paste" user "Package Geometry/Pastemask Bottom")
		(5 "F.SilkS" user "Ref Des/Silkscreen Top")
		(7 "B.SilkS" user "Ref Des/Silkscreen Bottom")
		(1 "F.Mask" user "Board Geometry/Soldermask Top")
		(3 "B.Mask" user "Board Geometry/Soldermask Bottom")
		(17 "Dwgs.User" user "User.Drawings")
		(19 "Cmts.User" user "User.Comments")
		(21 "Eco1.User" user "User.Eco1")
		(23 "Eco2.User" user "User.Eco2")
		(25 "Edge.Cuts" user "Board Geometry/Outline")
		(27 "Margin" user)
		(31 "F.CrtYd" user "Package Geometry/Place Bound Top")
		(29 "B.CrtYd" user "Package Geometry/Place Bound Bottom")
		(35 "F.Fab" user "Ref Des/Assembly Top")
		(33 "B.Fab" user "Ref Des/Assembly Bottom")
	)
	(footprint ""
		(layer "F.Cu")
		(at 175.4632 -96.103948 90)
		(property "Reference" "R238"
			(at 0 0 90)
			(layer "F.SilkS")
			(hide yes)
			(effects
				(font
					(size 1.27 1.27)
				)
			)
		)
		(property "Value" ""
			(at 0 0 90)
			(layer "F.Fab")
			(effects
				(font
					(size 1.27 1.27)
				)
			)
		)
		(duplicate_pad_numbers_are_jumpers no)
		(fp_line
			(start 0.7874 -0.4064)
			(end 0.7874 0.4064)
			(stroke
				(width 0.1524)
				(type default)
			)
			(layer "F.SilkS")
		)
		(fp_line
			(start -0.7874 -0.4064)
			(end 0.7874 -0.4064)
			(stroke
				(width 0.1524)
				(type default)
			)
			(layer "F.SilkS")
		)
		(fp_line
			(start 0.7874 0.4064)
			(end -0.7874 0.4064)
			(stroke
				(width 0.1524)
				(type default)
			)
			(layer "F.SilkS")
		)
		(fp_line
			(start -0.7874 0.4064)
			(end -0.7874 -0.4064)
			(stroke
				(width 0.1524)
				(type default)
			)
			(layer "F.SilkS")
		)
		(fp_line
			(start -0.12065 -0.305054)
			(end -0.12065 -0.2794)
			(stroke
				(width 0.1)
				(type default)
			)
			(layer "F.Fab")
		)
		(fp_line
			(start -0.67945 -0.305054)
			(end -0.12065 -0.305054)
			(stroke
				(width 0.1)
				(type default)
			)
			(layer "F.Fab")
		)
		(fp_line
			(start 0.67945 -0.3048)
			(end 0.67945 0.3048)
			(stroke
				(width 0.1)
				(type default)
			)
			(layer "F.Fab")
		)
		(fp_line
			(start 0.12065 -0.3048)
			(end 0.67945 -0.3048)
			(stroke
				(width 0.1)
				(type default)
			)
			(layer "F.Fab")
		)
		(fp_line
			(start 0.12065 -0.2794)
			(end 0.12065 -0.3048)
			(stroke
				(width 0.1)
				(type default)
			)
			(layer "F.Fab")
		)
		(fp_line
			(start -0.12065 -0.2794)
			(end 0.12065 -0.2794)
			(stroke
				(width 0.1)
				(type default)
			)
			(layer "F.Fab")
		)
		(fp_line
			(start 0.120396 0.2794)
			(end -0.12065 0.2794)
			(stroke
				(width 0.1)
				(type default)
			)
			(layer "F.Fab")
		)
		(fp_line
			(start -0.12065 0.2794)
			(end -0.12065 0.3048)
			(stroke
				(width 0.1)
				(type default)
			)
			(layer "F.Fab")
		)
		(fp_line
			(start 0.67945 0.3048)
			(end 0.120396 0.3048)
			(stroke
				(width 0.1)
				(type default)
			)
			(layer "F.Fab")
		)
		(fp_line
			(start 0.120396 0.3048)
			(end 0.120396 0.2794)
			(stroke
				(width 0.1)
				(type default)
			)
			(layer "F.Fab")
		)
		(fp_line
			(start -0.12065 0.3048)
			(end -0.67945 0.3048)
			(stroke
				(width 0.1)
				(type default)
			)
			(layer "F.Fab")
		)
		(fp_line
			(start -0.67945 0.3048)
			(end -0.67945 -0.305054)
			(stroke
				(width 0.1)
				(type default)
			)
			(layer "F.Fab")
		)
		(pad "1" smd circle
			(at -0.40005 0 90)
			(size 0 0)
			(layers "F.Cu" "F.Mask" "F.Paste")
			(net "CPU0_XTRIG_L6")
		)
		(pad "2" smd circle
			(at 0.40005 0 90)
			(size 0 0)
			(layers "F.Cu" "F.Mask" "F.Paste")
			(net "FM_CPU0_XTRIG_L6")
		)
	)
	(footprint ""
		(layer "F.Cu")
		(at 259.834126 -97.476056 180)
		(property "Reference" "R1634"
			(at 0 0 180)
			(layer "F.SilkS")
			(hide yes)
			(effects
				(font
					(size 1.27 1.27)
				)
			)
		)
		(property "Value" ""
			(at 0 0 180)
			(layer "F.Fab")
			(effects
				(font
					(size 1.27 1.27)
				)
			)
		)
		(duplicate_pad_numbers_are_jumpers no)
		(fp_line
			(start 0.7874 0.4064)
			(end -0.7874 0.4064)
			(stroke
				(width 0.1524)
				(type default)
			)
			(layer "F.SilkS")
		)
		(fp_line
			(start 0.7874 -0.4064)
			(end 0.7874 0.4064)
			(stroke
				(width 0.1524)
				(type default)
			)
			(layer "F.SilkS")
		)
		(fp_line
			(start -0.7874 0.4064)
			(end -0.7874 -0.4064)
			(stroke
				(width 0.1524)
				(type default)
			)
			(layer "F.SilkS")
		)
		(fp_line
			(start -0.7874 -0.4064)
			(end 0.7874 -0.4064)
			(stroke
				(width 0.1524)
				(type default)
			)
			(layer "F.SilkS")
		)
		(fp_line
			(start 0.67945 0.3048)
			(end 0.120396 0.3048)
			(stroke
				(width 0.1)
				(type default)
			)
			(layer "F.Fab")
		)
		(fp_line
			(start 0.67945 -0.3048)
			(end 0.67945 0.3048)
			(stroke
				(width 0.1)
				(type default)
			)
			(layer "F.Fab")
		)
		(fp_line
			(start 0.12065 -0.2794)
			(end 0.12065 -0.3048)
			(stroke
				(width 0.1)
				(type default)
			)
			(layer "F.Fab")
		)
		(fp_line
			(start 0.12065 -0.3048)
			(end 0.67945 -0.3048)
			(stroke
				(width 0.1)
				(type default)
			)
			(layer "F.Fab")
		)
		(fp_line
			(start 0.120396 0.3048)
			(end 0.120396 0.2794)
			(stroke
				(width 0.1)
				(type default)
			)
			(layer "F.Fab")
		)
		(fp_line
			(start 0.120396 0.2794)
			(end -0.12065 0.2794)
			(stroke
				(width 0.1)
				(type default)
			)
			(layer "F.Fab")
		)
		(fp_line
			(start -0.12065 0.3048)
			(end -0.67945 0.3048)
			(stroke
				(width 0.1)
				(type default)
			)
			(layer "F.Fab")
		)
		(fp_line
			(start -0.12065 0.2794)
			(end -0.12065 0.3048)
			(stroke
				(width 0.1)
				(type default)
			)
			(layer "F.Fab")
		)
		(fp_line
			(start -0.12065 -0.2794)
			(end 0.12065 -0.2794)
			(stroke
				(width 0.1)
				(type default)
			)
			(layer "F.Fab")
		)
		(fp_line
			(start -0.12065 -0.305054)
			(end -0.12065 -0.2794)
			(stroke
				(width 0.1)
				(type default)
			)
			(layer "F.Fab")
		)
		(fp_line
			(start -0.67945 0.3048)
			(end -0.67945 -0.305054)
			(stroke
				(width 0.1)
				(type default)
			)
			(layer "F.Fab")
		)
		(fp_line
			(start -0.67945 -0.305054)
			(end -0.12065 -0.305054)
			(stroke
				(width 0.1)
				(type default)
			)
			(layer "F.Fab")
		)
		(pad "1" smd circle
			(at -0.40005 0 180)
			(size 0 0)
			(layers "F.Cu" "F.Mask" "F.Paste")
			(net "JTAG_TMS_R")
		)
		(pad "2" smd circle
			(at 0.40005 0 180)
			(size 0 0)
			(layers "F.Cu" "F.Mask" "F.Paste")
			(net "JTAG_TMS")
		)
	)
	(footprint ""
		(layer "F.Cu")
		(at 57.872884 -408.517344 -90)
		(property "Reference" "C6635"
			(at 0 0 270)
			(layer "F.SilkS")
			(hide yes)
			(effects
				(font
					(size 1.27 1.27)
				)
			)
		)
		(property "Value" ""
			(at 0 0 270)
			(layer "F.Fab")
			(effects
				(font
					(size 1.27 1.27)
				)
			)
		)
		(duplicate_pad_numbers_are_jumpers no)
		(fp_line
			(start -0.299974 0.150114)
			(end -0.299974 -0.150114)
			(stroke
				(width 0.1)
				(type default)
			)
			(layer "F.Fab")
		)
		(fp_line
			(start 0.299974 0.150114)
			(end -0.299974 0.150114)
			(stroke
				(width 0.1)
				(type default)
			)
			(layer "F.Fab")
		)
		(fp_line
			(start -0.299974 -0.150114)
			(end 0.299974 -0.150114)
			(stroke
				(width 0.1)
				(type default)
			)
			(layer "F.Fab")
		)
		(fp_line
			(start 0.299974 -0.150114)
			(end 0.299974 0.150114)
			(stroke
				(width 0.1)
				(type default)
			)
			(layer "F.Fab")
		)
		(pad "1" smd rect
			(at -0.2667 0 270)
			(size 0.3048 0.381)
			(layers "F.Cu" "F.Mask" "F.Paste")
			(net "P5E_CPU1_P0_TX_BUF_C_DP<3>")
		)
		(pad "2" smd rect
			(at 0.2667 0 270)
			(size 0.3048 0.381)
			(layers "F.Cu" "F.Mask" "F.Paste")
			(net "P5E_CPU1_P0_TX_BUF_DP<3>")
		)
	)
)
